(kicad_pcb
	(version 20241229)
	(generator "pcbnew")
	(generator_version "9.0")
	(general
		(thickness 1.258)
		(legacy_teardrops no)
	)
	(paper "A4")
	(title_block
		(date "2024-05-27")
		(rev "1.1.2")
		(comment 9 "footprints 1-1 of 64")
	)
	(layers
		(0 "F.Cu" signal)
		(4 "In1.Cu" power)
		(6 "In2.Cu" power)
		(8 "In3.Cu" signal)
		(10 "In4.Cu" signal)
		(2 "B.Cu" signal)
		(9 "F.Adhes" user "F.Adhesive")
		(11 "B.Adhes" user "B.Adhesive")
		(13 "F.Paste" user)
		(15 "B.Paste" user)
		(5 "F.SilkS" user "F.Silkscreen")
		(7 "B.SilkS" user "B.Silkscreen")
		(1 "F.Mask" user)
		(3 "B.Mask" user)
		(17 "Dwgs.User" user "User.Drawings")
		(19 "Cmts.User" user "User.Comments")
		(21 "Eco1.User" user "User.Eco1")
		(23 "Eco2.User" user "User.Eco2")
		(25 "Edge.Cuts" user)
		(27 "Margin" user)
		(31 "F.CrtYd" user "F.Courtyard")
		(29 "B.CrtYd" user "B.Courtyard")
		(35 "F.Fab" user)
		(33 "B.Fab" user)
	)
	(footprint "antmicro-footprints:antmicro-logo_scaled_20mm"
		(layer "F.Cu")
		(at 112.225 74.9)
		(property "Reference" "N1"
			(at 0.05 -5.5 0)
			(layer "F.SilkS")
			(hide yes)
			(effects
				(font
					(size 0.7 0.7)
					(thickness 0.15)
				)
				(justify left bottom)
			)
		)
		(property "Value" "antmicro_logo"
			(at -0.101 5.099 0)
			(layer "F.SilkS")
			(hide yes)
			(effects
				(font
					(size 0.7 0.7)
					(thickness 0.15)
				)
				(justify left bottom)
			)
		)
		(property "Author" "Antmicro"
			(at 0 0 0)
			(layer "F.Fab")
			(hide yes)
			(effects
				(font
					(size 1 1)
					(thickness 0.15)
				)
			)
		)
		(property "License" "Apache-2.0"
			(at 0 0 0)
			(layer "F.Fab")
			(hide yes)
			(effects
				(font
					(size 1 1)
					(thickness 0.15)
				)
			)
		)
		(property "MPN" ""
			(at 0 0 0)
			(layer "F.Fab")
			(hide yes)
			(effects
				(font
					(size 1 1)
					(thickness 0.15)
				)
			)
		)
		(property "Manufacturer" ""
			(at 0 0 0)
			(layer "F.Fab")
			(hide yes)
			(effects
				(font
					(size 1 1)
					(thickness 0.15)
				)
			)
		)
		(sheetfile "ddr5-testbed.kicad_sch")
		(attr allow_soldermask_bridges)
	)
)
